(kicad_pcb
	(version 20260206)
	(generator "pcbnew")
	(generator_version "10.0")
	(general
		(thickness 1.6)
		(legacy_teardrops no)
	)
	(paper "A4")
	(title_block
		(title "Wiwynn_Tioga_Pass_MB.brd")
		(comment 1 "Tioga Pass / footprints 2799-2806 of 4770")
	)
	(layers
		(0 "F.Cu" signal "TOP")
		(4 "In1.Cu" signal "L2GND")
		(6 "In2.Cu" signal "L3")
		(8 "In3.Cu" signal "L4GND")
		(10 "In4.Cu" signal "L5")
		(12 "In5.Cu" signal "L6GND")
		(14 "In6.Cu" signal "L7VCC")
		(16 "In7.Cu" signal "L8VCC")
		(18 "In8.Cu" signal "L9GND")
		(20 "In9.Cu" signal "L10")
		(22 "In10.Cu" signal "L11GND")
		(24 "In11.Cu" signal "L12")
		(26 "In12.Cu" signal "L13GND")
		(2 "B.Cu" signal "BOTTOM")
		(9 "F.Adhes" user "F.Adhesive")
		(11 "B.Adhes" user "B.Adhesive")
		(13 "F.Paste" user "Package Geometry/Pastemask Top")
		(15 "B.Paste" user "Package Geometry/Pastemask Bottom")
		(5 "F.SilkS" user "Ref Des/Silkscreen Top")
		(7 "B.SilkS" user "Ref Des/Silkscreen Bottom")
		(1 "F.Mask" user "Board Geometry/Soldermask Top")
		(3 "B.Mask" user "Board Geometry/Soldermask Bottom")
		(17 "Dwgs.User" user "User.Drawings")
		(19 "Cmts.User" user "User.Comments")
		(21 "Eco1.User" user "User.Eco1")
		(23 "Eco2.User" user "User.Eco2")
		(25 "Edge.Cuts" user "Board Geometry/Outline")
		(27 "Margin" user)
		(31 "F.CrtYd" user "Package Geometry/Place Bound Top")
		(29 "B.CrtYd" user "Package Geometry/Place Bound Bottom")
		(35 "F.Fab" user "Ref Des/Assembly Top")
		(33 "B.Fab" user "Ref Des/Assembly Bottom")
	)
	(footprint ""
		(layer "B.Cu")
		(at 115.353592 -71.841614 180)
		(property "Reference" "C7P16"
			(at 0 0 0)
			(layer "B.SilkS")
			(hide yes)
			(effects
				(font
					(size 1.27 1.27)
				)
				(justify mirror)
			)
		)
		(property "Value" ""
			(at 0 0 0)
			(layer "B.Fab")
			(effects
				(font
					(size 1.27 1.27)
				)
				(justify mirror)
			)
		)
		(duplicate_pad_numbers_are_jumpers no)
		(fp_poly
			(pts
				(xy 0.4953 -0.2032) (xy -0.4953 -0.2032) (xy -0.4953 1.6002) (xy 0.4953 1.6002)
			)
			(stroke
				(width 0)
				(type default)
			)
			(fill no)
			(layer "B.CrtYd")
		)
		(fp_line
			(start 0.4953 1.6002)
			(end 0.4953 -0.2032)
			(stroke
				(width 0.1)
				(type default)
			)
			(layer "B.Fab")
		)
		(fp_line
			(start 0.4953 -0.2032)
			(end -0.4953 -0.2032)
			(stroke
				(width 0.1)
				(type default)
			)
			(layer "B.Fab")
		)
		(fp_line
			(start -0.4953 1.6002)
			(end 0.4953 1.6002)
			(stroke
				(width 0.1)
				(type default)
			)
			(layer "B.Fab")
		)
		(fp_line
			(start -0.4953 -0.2032)
			(end -0.4953 1.6002)
			(stroke
				(width 0.1)
				(type default)
			)
			(layer "B.Fab")
		)
		(pad "1" smd rect
			(at 0 0)
			(size 0.762 0.889)
			(layers "B.Cu" "B.Mask" "B.Paste")
			(net "PVCCIO_CPU1")
		)
		(pad "2" smd rect
			(at 0 1.397)
			(size 0.762 0.889)
			(layers "B.Cu" "B.Mask" "B.Paste")
			(net "GND")
		)
		(zone
			(layer "B.Cu")
			(hatch none 0.5)
			(connect_pads
				(clearance 0)
			)
			(min_thickness 0.25)
			(keepout
				(tracks not_allowed)
				(vias allowed)
				(pads allowed)
				(copperpour not_allowed)
				(footprints allowed)
			)
			(placement
				(enabled no)
				(sheetname "")
			)
			(fill
				(thermal_gap 0.5)
				(thermal_bridge_width 0.5)
				(island_removal_mode 0)
			)
			(polygon
				(pts
					(xy 114.972592 -72.286114) (xy 115.734592 -72.286114) (xy 115.734592 -72.794114) (xy 114.972592 -72.794114)
				)
			)
		)
	)
	(footprint ""
		(layer "B.Cu")
		(at 107.8611 -12.954 90)
		(property "Reference" "C5G95"
			(at -1.14681 0.76708 180)
			(unlocked yes)
			(layer "B.SilkS")
			(effects
				(font
					(size 0.7874 0.5842)
					(thickness 0.1524)
				)
				(justify mirror)
			)
		)
		(property "Value" ""
			(at 0 0 90)
			(layer "B.Fab")
			(effects
				(font
					(size 1.27 1.27)
				)
				(justify mirror)
			)
		)
		(duplicate_pad_numbers_are_jumpers no)
		(fp_rect
			(start -0.4953 -0.2032)
			(end 0.4953 1.6002)
			(stroke
				(width 0)
				(type default)
			)
			(fill no)
			(layer "B.CrtYd")
		)
		(fp_line
			(start 0.4953 -0.2032)
			(end -0.4953 -0.2032)
			(stroke
				(width 0.1)
				(type default)
			)
			(layer "B.Fab")
		)
		(fp_line
			(start -0.4953 -0.2032)
			(end -0.4953 1.6002)
			(stroke
				(width 0.1)
				(type default)
			)
			(layer "B.Fab")
		)
		(fp_line
			(start 0.4953 1.6002)
			(end 0.4953 -0.2032)
			(stroke
				(width 0.1)
				(type default)
			)
			(layer "B.Fab")
		)
		(fp_line
			(start -0.4953 1.6002)
			(end 0.4953 1.6002)
			(stroke
				(width 0.1)
				(type default)
			)
			(layer "B.Fab")
		)
		(pad "1" smd rect
			(at 0 0 270)
			(size 0.762 0.889)
			(layers "B.Cu" "B.Mask" "B.Paste")
			(net "PVDDQ_GHJ")
		)
		(pad "2" smd rect
			(at 0 1.397 270)
			(size 0.762 0.889)
			(layers "B.Cu" "B.Mask" "B.Paste")
			(net "GND")
		)
		(zone
			(layer "B.Cu")
			(hatch none 0.5)
			(connect_pads
				(clearance 0)
			)
			(min_thickness 0.25)
			(keepout
				(tracks not_allowed)
				(vias allowed)
				(pads allowed)
				(copperpour not_allowed)
				(footprints allowed)
			)
			(placement
				(enabled no)
				(sheetname "")
			)
			(fill
				(thermal_gap 0.5)
				(thermal_bridge_width 0.5)
				(island_removal_mode 0)
			)
			(polygon
				(pts
					(xy 108.3056 -12.573) (xy 108.8136 -12.573) (xy 108.8136 -13.335) (xy 108.3056 -13.335)
				)
			)
		)
	)
	(footprint ""
		(layer "B.Cu")
		(at 374.381268 -48.328326 90)
		(property "Reference" "R2T59"
			(at 0 0 90)
			(layer "B.SilkS")
			(hide yes)
			(effects
				(font
					(size 1.27 1.27)
				)
				(justify mirror)
			)
		)
		(property "Value" ""
			(at 0 0 90)
			(layer "B.Fab")
			(effects
				(font
					(size 1.27 1.27)
				)
				(justify mirror)
			)
		)
		(duplicate_pad_numbers_are_jumpers no)
		(fp_poly
			(pts
				(xy 0.2794 -0.1016) (xy -0.2794 -0.1016) (xy -0.2794 0.9906) (xy 0.2794 0.9906)
			)
			(stroke
				(width 0)
				(type default)
			)
			(fill no)
			(layer "B.CrtYd")
		)
		(fp_line
			(start 0.2794 -0.1016)
			(end 0.2794 0.9906)
			(stroke
				(width 0.1)
				(type default)
			)
			(layer "B.Fab")
		)
		(fp_line
			(start -0.2794 -0.1016)
			(end 0.2794 -0.1016)
			(stroke
				(width 0.1)
				(type default)
			)
			(layer "B.Fab")
		)
		(fp_line
			(start 0.2794 0.9906)
			(end -0.2794 0.9906)
			(stroke
				(width 0.1)
				(type default)
			)
			(layer "B.Fab")
		)
		(fp_line
			(start -0.2794 0.9906)
			(end -0.2794 -0.1016)
			(stroke
				(width 0.1)
				(type default)
			)
			(layer "B.Fab")
		)
		(pad "1" smd rect
			(at 0 0 270)
			(size 0.508 0.508)
			(layers "B.Cu" "B.Mask" "B.Paste")
			(net "H_CPU0_PROCHOT_G_N")
		)
		(pad "2" smd rect
			(at 0 0.889 270)
			(size 0.508 0.508)
			(layers "B.Cu" "B.Mask" "B.Paste")
			(net "H_CPU0_PROCHOT_G_PCH_N")
		)
		(zone
			(layer "B.Cu")
			(hatch none 0.5)
			(connect_pads
				(clearance 0)
			)
			(min_thickness 0.25)
			(keepout
				(tracks allowed)
				(vias not_allowed)
				(pads allowed)
				(copperpour not_allowed)
				(footprints allowed)
			)
			(placement
				(enabled no)
				(sheetname "")
			)
			(fill
				(thermal_gap 0.5)
				(thermal_bridge_width 0.5)
				(island_removal_mode 0)
			)
			(polygon
				(pts
					(xy 374.635268 -48.582326) (xy 374.635268 -48.074326) (xy 375.016268 -48.074326) (xy 375.016268 -48.582326)
				)
			)
		)
		(zone
			(layer "B.Cu")
			(hatch none 0.5)
			(connect_pads
				(clearance 0)
			)
			(min_thickness 0.25)
			(keepout
				(tracks not_allowed)
				(vias allowed)
				(pads allowed)
				(copperpour not_allowed)
				(footprints allowed)
			)
			(placement
				(enabled no)
				(sheetname "")
			)
			(fill
				(thermal_gap 0.5)
				(thermal_bridge_width 0.5)
				(island_removal_mode 0)
			)
			(polygon
				(pts
					(xy 375.016268 -48.582326) (xy 375.016268 -48.074326) (xy 374.635268 -48.074326) (xy 374.635268 -48.582326)
				)
			)
		)
	)
	(footprint ""
		(layer "B.Cu")
		(at 469.646 -134.7978 90)
		(property "Reference" "R6W35"
			(at 0.8382 -0.67818 90)
			(unlocked yes)
			(layer "B.SilkS")
			(effects
				(font
					(size 0.4064 0.254)
					(thickness 0.1524)
				)
				(justify left mirror)
			)
		)
		(property "Value" ""
			(at 0 0 90)
			(layer "B.Fab")
			(effects
				(font
					(size 1.27 1.27)
				)
				(justify mirror)
			)
		)
		(duplicate_pad_numbers_are_jumpers no)
		(fp_poly
			(pts
				(xy 0.2794 -0.1016) (xy -0.2794 -0.1016) (xy -0.2794 0.9906) (xy 0.2794 0.9906)
			)
			(stroke
				(width 0)
				(type default)
			)
			(fill no)
			(layer "B.CrtYd")
		)
		(fp_line
			(start 0.2794 -0.1016)
			(end 0.2794 0.9906)
			(stroke
				(width 0.1)
				(type default)
			)
			(layer "B.Fab")
		)
		(fp_line
			(start -0.2794 -0.1016)
			(end 0.2794 -0.1016)
			(stroke
				(width 0.1)
				(type default)
			)
			(layer "B.Fab")
		)
		(fp_line
			(start 0.2794 0.9906)
			(end -0.2794 0.9906)
			(stroke
				(width 0.1)
				(type default)
			)
			(layer "B.Fab")
		)
		(fp_line
			(start -0.2794 0.9906)
			(end -0.2794 -0.1016)
			(stroke
				(width 0.1)
				(type default)
			)
			(layer "B.Fab")
		)
		(pad "1" smd rect
			(at 0 0 270)
			(size 0.508 0.508)
			(layers "B.Cu" "B.Mask" "B.Paste")
			(net "P3V3_STBY")
		)
		(pad "2" smd rect
			(at 0 0.889 270)
			(size 0.508 0.508)
			(layers "B.Cu" "B.Mask" "B.Paste")
			(net "FM_CPU_CATERR_MSMI_LVT3_N")
		)
		(zone
			(layer "B.Cu")
			(hatch none 0.5)
			(connect_pads
				(clearance 0)
			)
			(min_thickness 0.25)
			(keepout
				(tracks allowed)
				(vias not_allowed)
				(pads allowed)
				(copperpour not_allowed)
				(footprints allowed)
			)
			(placement
				(enabled no)
				(sheetname "")
			)
			(fill
				(thermal_gap 0.5)
				(thermal_bridge_width 0.5)
				(island_removal_mode 0)
			)
			(polygon
				(pts
					(xy 469.9 -135.0518) (xy 469.9 -134.5438) (xy 470.281 -134.5438) (xy 470.281 -135.0518)
				)
			)
		)
		(zone
			(layer "B.Cu")
			(hatch none 0.5)
			(connect_pads
				(clearance 0)
			)
			(min_thickness 0.25)
			(keepout
				(tracks not_allowed)
				(vias allowed)
				(pads allowed)
				(copperpour not_allowed)
				(footprints allowed)
			)
			(placement
				(enabled no)
				(sheetname "")
			)
			(fill
				(thermal_gap 0.5)
				(thermal_bridge_width 0.5)
				(island_removal_mode 0)
			)
			(polygon
				(pts
					(xy 470.281 -135.0518) (xy 470.281 -134.5438) (xy 469.9 -134.5438) (xy 469.9 -135.0518)
				)
			)
		)
	)
	(footprint ""
		(layer "B.Cu")
		(at 26.0096 -79.502 -90)
		(property "Reference" "U9P2"
			(at -1.3716 -1.44653 270)
			(unlocked yes)
			(layer "B.SilkS")
			(effects
				(font
					(size 0.7874 0.5842)
					(thickness 0.1524)
				)
				(justify mirror)
			)
		)
		(property "Value" ""
			(at 0 0 90)
			(layer "B.Fab")
			(effects
				(font
					(size 1.27 1.27)
				)
				(justify mirror)
			)
		)
		(duplicate_pad_numbers_are_jumpers no)
		(fp_circle
			(center 0.8255 0.199898)
			(end 0.8255 0.072644)
			(stroke
				(width 0.254)
				(type default)
			)
			(fill no)
			(layer "B.SilkS")
		)
		(fp_rect
			(start 0.216154 1.27508)
			(end -1.333754 -0.275082)
			(stroke
				(width 0)
				(type default)
			)
			(fill no)
			(layer "B.CrtYd")
		)
		(fp_line
			(start -1.333754 1.27508)
			(end 0.216154 1.27508)
			(stroke
				(width 0.1)
				(type default)
			)
			(layer "B.Fab")
		)
		(fp_line
			(start 0.216154 1.27508)
			(end 0.216154 -0.275082)
			(stroke
				(width 0.1)
				(type default)
			)
			(layer "B.Fab")
		)
		(fp_line
			(start -1.333754 -0.275082)
			(end -1.333754 1.27508)
			(stroke
				(width 0.1)
				(type default)
			)
			(layer "B.Fab")
		)
		(fp_line
			(start 0.216154 -0.275082)
			(end -1.333754 -0.275082)
			(stroke
				(width 0.1)
				(type default)
			)
			(layer "B.Fab")
		)
		(fp_circle
			(center 1.0795 -0.054102)
			(end 1.0795 -0.181356)
			(stroke
				(width 0.254)
				(type default)
			)
			(fill no)
			(layer "B.Fab")
		)
		(pad "1" smd rect
			(at 0 0 90)
			(size 0.9398 0.3048)
			(layers "B.Cu" "B.Mask" "B.Paste")
			(net "FM_HSC_TIMER_EXP_N")
		)
		(pad "2" smd rect
			(at 0.0254 0.500126 90)
			(size 0.889 0.3048)
			(layers "B.Cu" "B.Mask" "B.Paste")
			(net "P3V3_STBY")
		)
		(pad "3" smd rect
			(at 0.0254 0.999998 90)
			(size 0.889 0.3048)
			(layers "B.Cu" "B.Mask" "B.Paste")
			(net "A_HSC_TIMER_R")
		)
		(pad "4" smd rect
			(at -1.143 0.999998 90)
			(size 0.889 0.3048)
			(layers "B.Cu" "B.Mask" "B.Paste")
			(net "A_HSC_INAP")
		)
		(pad "5" smd rect
			(at -1.143 0.500126 90)
			(size 0.889 0.3048)
			(layers "B.Cu" "B.Mask" "B.Paste")
			(net "GND")
		)
		(pad "6" smd rect
			(at -1.143 0 90)
			(size 0.889 0.3048)
			(layers "B.Cu" "B.Mask" "B.Paste")
			(net "PWRGD_DSW_PWROK")
		)
	)
	(footprint ""
		(layer "B.Cu")
		(at 22.606 -77.724 180)
		(property "Reference" "R9P17"
			(at 0 0 0)
			(layer "B.SilkS")
			(hide yes)
			(effects
				(font
					(size 1.27 1.27)
				)
				(justify mirror)
			)
		)
		(property "Value" ""
			(at 0 0 0)
			(layer "B.Fab")
			(effects
				(font
					(size 1.27 1.27)
				)
				(justify mirror)
			)
		)
		(duplicate_pad_numbers_are_jumpers no)
		(fp_rect
			(start 0.2794 -0.1016)
			(end -0.2794 0.9906)
			(stroke
				(width 0)
				(type default)
			)
			(fill no)
			(layer "B.CrtYd")
		)
		(fp_line
			(start 0.2794 0.9906)
			(end -0.2794 0.9906)
			(stroke
				(width 0.1)
				(type default)
			)
			(layer "B.Fab")
		)
		(fp_line
			(start 0.2794 -0.1016)
			(end 0.2794 0.9906)
			(stroke
				(width 0.1)
				(type default)
			)
			(layer "B.Fab")
		)
		(fp_line
			(start -0.2794 0.9906)
			(end -0.2794 -0.1016)
			(stroke
				(width 0.1)
				(type default)
			)
			(layer "B.Fab")
		)
		(fp_line
			(start -0.2794 -0.1016)
			(end 0.2794 -0.1016)
			(stroke
				(width 0.1)
				(type default)
			)
			(layer "B.Fab")
		)
		(pad "1" smd rect
			(at 0 0)
			(size 0.508 0.508)
			(layers "B.Cu" "B.Mask" "B.Paste")
			(net "FM_P12V_HSC_ADR1")
		)
		(pad "2" smd rect
			(at 0 0.889)
			(size 0.508 0.508)
			(layers "B.Cu" "B.Mask" "B.Paste")
			(net "AGND_HSC")
		)
		(zone
			(layer "B.Cu")
			(hatch none 0.5)
			(connect_pads
				(clearance 0)
			)
			(min_thickness 0.25)
			(keepout
				(tracks not_allowed)
				(vias allowed)
				(pads allowed)
				(copperpour not_allowed)
				(footprints allowed)
			)
			(placement
				(enabled no)
				(sheetname "")
			)
			(fill
				(thermal_gap 0.5)
				(thermal_bridge_width 0.5)
				(island_removal_mode 0)
			)
			(polygon
				(pts
					(xy 22.352 -77.978) (xy 22.86 -77.978) (xy 22.86 -78.359) (xy 22.352 -78.359)
				)
			)
		)
		(zone
			(layer "B.Cu")
			(hatch none 0.5)
			(connect_pads
				(clearance 0)
			)
			(min_thickness 0.25)
			(keepout
				(tracks allowed)
				(vias not_allowed)
				(pads allowed)
				(copperpour not_allowed)
				(footprints allowed)
			)
			(placement
				(enabled no)
				(sheetname "")
			)
			(fill
				(thermal_gap 0.5)
				(thermal_bridge_width 0.5)
				(island_removal_mode 0)
			)
			(polygon
				(pts
					(xy 22.352 -77.978) (xy 22.86 -77.978) (xy 22.86 -78.359) (xy 22.352 -78.359)
				)
			)
		)
	)
	(footprint ""
		(layer "B.Cu")
		(at 107.8611 -17.7546 90)
		(property "Reference" "C7T5"
			(at -1.848866 0.752348 90)
			(unlocked yes)
			(layer "B.SilkS")
			(effects
				(font
					(size 1.27 0.9652)
					(thickness 0.1524)
				)
				(justify mirror)
			)
		)
		(property "Value" ""
			(at 0 0 90)
			(layer "B.Fab")
			(effects
				(font
					(size 1.27 1.27)
				)
				(justify mirror)
			)
		)
		(duplicate_pad_numbers_are_jumpers no)
		(fp_rect
			(start 0.500126 1.598422)
			(end -0.500126 -0.201422)
			(stroke
				(width 0)
				(type default)
			)
			(fill no)
			(layer "B.CrtYd")
		)
		(fp_line
			(start 0.500126 -0.201422)
			(end -0.500126 -0.201422)
			(stroke
				(width 0.1)
				(type default)
			)
			(layer "B.Fab")
		)
		(fp_line
			(start -0.500126 -0.201422)
			(end -0.500126 1.598422)
			(stroke
				(width 0.1)
				(type default)
			)
			(layer "B.Fab")
		)
		(fp_line
			(start 0.500126 1.598422)
			(end 0.500126 -0.201422)
			(stroke
				(width 0.1)
				(type default)
			)
			(layer "B.Fab")
		)
		(fp_line
			(start -0.500126 1.598422)
			(end 0.500126 1.598422)
			(stroke
				(width 0.1)
				(type default)
			)
			(layer "B.Fab")
		)
		(pad "1" smd rect
			(at 0 0)
			(size 0.889 0.9906)
			(layers "B.Cu" "B.Mask" "B.Paste")
			(net "PVDDQ_GHJ")
		)
		(pad "2" smd rect
			(at 0 1.397)
			(size 0.889 0.9906)
			(layers "B.Cu" "B.Mask" "B.Paste")
			(net "GND")
		)
		(zone
			(layer "B.Cu")
			(hatch none 0.5)
			(connect_pads
				(clearance 0)
			)
			(min_thickness 0.25)
			(keepout
				(tracks not_allowed)
				(vias allowed)
				(pads allowed)
				(copperpour not_allowed)
				(footprints allowed)
			)
			(placement
				(enabled no)
				(sheetname "")
			)
			(fill
				(thermal_gap 0.5)
				(thermal_bridge_width 0.5)
				(island_removal_mode 0)
			)
			(polygon
				(pts
					(xy 108.8136 -18.2499) (xy 108.3056 -18.2499) (xy 108.3056 -17.2593) (xy 108.8136 -17.2593)
				)
			)
		)
		(zone
			(layer "B.Cu")
			(hatch none 0.5)
			(connect_pads
				(clearance 0)
			)
			(min_thickness 0.25)
			(keepout
				(tracks allowed)
				(vias not_allowed)
				(pads allowed)
				(copperpour not_allowed)
				(footprints allowed)
			)
			(placement
				(enabled no)
				(sheetname "")
			)
			(fill
				(thermal_gap 0.5)
				(thermal_bridge_width 0.5)
				(island_removal_mode 0)
			)
			(polygon
				(pts
					(xy 108.8136 -18.2499) (xy 108.3056 -18.2499) (xy 108.3056 -17.2593) (xy 108.8136 -17.2593)
				)
			)
		)
	)
	(footprint ""
		(layer "B.Cu")
		(at 427.38675 -13.010642 90)
		(property "Reference" "R9G27"
			(at 0 0 90)
			(layer "B.SilkS")
			(hide yes)
			(effects
				(font
					(size 1.27 1.27)
				)
				(justify mirror)
			)
		)
		(property "Value" ""
			(at 0 0 90)
			(layer "B.Fab")
			(effects
				(font
					(size 1.27 1.27)
				)
				(justify mirror)
			)
		)
		(duplicate_pad_numbers_are_jumpers no)
		(fp_poly
			(pts
				(xy 0.2794 -0.1016) (xy -0.2794 -0.1016) (xy -0.2794 0.9906) (xy 0.2794 0.9906)
			)
			(stroke
				(width 0)
				(type default)
			)
			(fill no)
			(layer "B.CrtYd")
		)
		(fp_line
			(start 0.2794 -0.1016)
			(end 0.2794 0.9906)
			(stroke
				(width 0.1)
				(type default)
			)
			(layer "B.Fab")
		)
		(fp_line
			(start -0.2794 -0.1016)
			(end 0.2794 -0.1016)
			(stroke
				(width 0.1)
				(type default)
			)
			(layer "B.Fab")
		)
		(fp_line
			(start 0.2794 0.9906)
			(end -0.2794 0.9906)
			(stroke
				(width 0.1)
				(type default)
			)
			(layer "B.Fab")
		)
		(fp_line
			(start -0.2794 0.9906)
			(end -0.2794 -0.1016)
			(stroke
				(width 0.1)
				(type default)
			)
			(layer "B.Fab")
		)
		(pad "1" smd rect
			(at 0 0 270)
			(size 0.508 0.508)
			(layers "B.Cu" "B.Mask" "B.Paste")
			(net "H_CPU0_MEMDEF_MEMHOT_G_PCH_N")
		)
		(pad "2" smd rect
			(at 0 0.889 270)
			(size 0.508 0.508)
			(layers "B.Cu" "B.Mask" "B.Paste")
			(net "H_CPU0_MEMDEF_MEMHOT_LVT3_K_N")
		)
		(zone
			(layer "B.Cu")
			(hatch none 0.5)
			(connect_pads
				(clearance 0)
			)
			(min_thickness 0.25)
			(keepout
				(tracks allowed)
				(vias not_allowed)
				(pads allowed)
				(copperpour not_allowed)
				(footprints allowed)
			)
			(placement
				(enabled no)
				(sheetname "")
			)
			(fill
				(thermal_gap 0.5)
				(thermal_bridge_width 0.5)
				(island_removal_mode 0)
			)
			(polygon
				(pts
					(xy 427.64075 -13.264642) (xy 427.64075 -12.756642) (xy 428.02175 -12.756642) (xy 428.02175 -13.264642)
				)
			)
		)
		(zone
			(layer "B.Cu")
			(hatch none 0.5)
			(connect_pads
				(clearance 0)
			)
			(min_thickness 0.25)
			(keepout
				(tracks not_allowed)
				(vias allowed)
				(pads allowed)
				(copperpour not_allowed)
				(footprints allowed)
			)
			(placement
				(enabled no)
				(sheetname "")
			)
			(fill
				(thermal_gap 0.5)
				(thermal_bridge_width 0.5)
				(island_removal_mode 0)
			)
			(polygon
				(pts
					(xy 428.02175 -13.264642) (xy 428.02175 -12.756642) (xy 427.64075 -12.756642) (xy 427.64075 -13.264642)
				)
			)
		)
	)
)
